FILE_TYPE = MACRO_DRAWING;
SET COLOR_WIRE YELLOW;
SET COLOR_PROP ORANGE;
SET COLOR_DOT WHITE;
SET COLOR_ARC YELLOW;
SET COLOR_BODY GREEN;
SET COLOR_NOTE PURPLE;
SET PROP_DISPLAY VALUE;
SET PAGE_NUMBER P455;
FORCEADD QUANTA_TITLE_BLOCK_C..1
(0 0);
FORCEPROP 1 LAST CUSTOM_TXT_CDS <NAME_2>
J 0
(-3175 50);
FORCEPROP 1 LAST CUSTOM_TXT_CDS <NAME_1>
J 0
(-3175 175);
FORCEPROP 1 LAST CUSTOM_TXT_CDS <Q_NUMBER>
J 0
(-1403 103);
DISPLAY 1.212766 (-1403 103);
FORCEPROP 1 LAST CUSTOM_TXT_CDS <Q_PROJ>
J 0
(-2382 102);
DISPLAY 1.212766 (-2382 102);
FORCEPROP 1 LAST CUSTOM_TXT_CDS <Q_REV>
J 0
(-184 103);
DISPLAY 1.212766 (-184 103);
FORCEPROP 1 LAST CUSTOM_TXT_CDS <CON_LAST_MODIFIED>
J 0
(-1885 15);
DISPLAY 0.978723 (-1885 15);
FORCEPROP 1 LAST CUSTOM_TXT_CDS <CON_PAGE_NUM> OF <CON_TOTAL_PAGES>
J 0
(-446 18);
DISPLAY 0.978723 (-446 18);
FORCEPROP 1 LAST Q_TITLE RETIMER_CPU1_P2(9)
J 0
(-9366 26);
DISPLAY 2.446809 (-9366 26);
PAINT GREEN (-9366 26);
FORCEPROP 2 LAST CDS_LIB pure_quanta
J 0
(0 0);
DISPLAY INVISIBLE (0 0);
FORCEPROP 1 LAST CDS_LMAN_SYM_OUTLINE -9475,6775,100,-125
J 0
(0 0);
DISPLAY 0.468085 (0 0);
PAINT GREEN (0 0);
DISPLAY INVISIBLE (0 0);
FORCEPROP 2 LAST PAGE_BORDER TRUE
J 0
(-7890 5250);
DISPLAY 0.638298 (-7890 5250);
PAINT PINK (-7890 5250);
DISPLAY INVISIBLE (-7890 5250);
FORCEPROP 2 LAST CDS_XR_PAGE_TITLE CR-347 : @T6G_MB_LIB.T6G(SCH_1):PAGE347
J 0
(-7890 5250);
DISPLAY 0.638298 (-7890 5250);
PAINT PINK (-7890 5250);
DISPLAY INVISIBLE (-7890 5250);
FORCEPROP 2 LAST CUSTOM_TXT_CDS <XR_PAGE_TITLE>
J 0
(-7890 5250);
DISPLAY 0.638298 (-7890 5250);
PAINT PINK (-7890 5250);
DISPLAY INVISIBLE (-7890 5250);
FORCEPROP 1 LAST COMMENT_BODY TRUE
J 0
(12 -13);
DISPLAY 0.978723 (12 -13);
PAINT GREEN (12 -13);
DISPLAY INVISIBLE (12 -13);
FORCEPROP 1 LAST Q_DEPT BU9
J 1
(-3763 49);
DISPLAY 1.957447 (-3763 49);
PAINT GREEN (-3763 49);
DISPLAY INVISIBLE (-3763 49);
FORCEPROP 0 LAST CDS_CON_LAST_MODIFIED Thu Aug 24 10:17:04 2023
J 0
(-1885 15);
DISPLAY INVISIBLE (-1885 15);
QUIT
